FILE_TYPE = CONNECTIVITY;
{Allegro Design Entry HDL 16.6-p007 (v16-6-112F) 10/10/2012}
"PAGE_NUMBER" = 150;
0"NC";
1"P3V3_STBY\g";
2"GND\g";
3"GND\g";
4"GND\g";
5"GND\g";
6"GND\g";
7"GND\g";
8"GND\g";
9"P3V3_STBY\g";
10"TP_RGMII1TXD3_GPIOT5";
11"TP_RGMII1TXD2_GPIOT4";
12"RMII_BMC_PCH_SPRNGVLLE_TXD0_R";
13"RMII_BMC_OCP_TXD1_R";
14"BMC_STRAP_BIT17";
15"GPIOS7";
16"BMC_STRAP_BIT27";
17"BMC_STRAP_BIT20";
18"BMC_STRAP_BIT18";
19"BMC_STRAP_BIT5";
20"BMC_STRAP_BIT3";
21"SPI_BMC_BT_DO";
22"TP_RGMII2TXD2_GPIOU2";
23"TP_RGMII2TXD3_GPIOU3";
24"RMII_BMC_PCH_SPRNGVLLE_TXD1_R";
25"RMII_BMC_PCH_SPRNGVLLE_TXEN";
26"RMII_BMC_OCP_TXD0_R";
27"RMII_BMC_OCP_TXEN";
28"UART_BMC_TXD5";
29"PU_JTAG_BMC_RTCK";
30"SPI_BMC_BT_DI";
31"SPI_BMC_BT_CLK";
%"RES"
"1","(-600,200)","0","mstr_discrete","I144";
;
CDS_SEC"1"
LOCATION"R25W95"
MATERIAL"CHIP"
TOLERANCE"1%"
PART_NUMBER"G21796-072"
WATTAGE"1/16W"
VALUE"4.75K"
PACK_TYPE"0402"
SEC"1"
SEC_TYPE"0402"
CDS_LOCATION"R25W95"
ROOM"BMC"
BOM_COST"SM_CONTROLLER"
CDS_LIB"mstr_discrete";
"B"
$PN"2"31;
"A"
$PN"1"1;
%"RES"
"1","(-600,0)","0","mstr_discrete","I145";
;
CDS_SEC"1"
TOLERANCE"1%"
VALUE"4.75K"
MATERIAL"CHIP"
PART_NUMBER"G21796-072"
WATTAGE"1/16W"
PACK_TYPE"0402"
LOCATION"R25W96"
SEC_TYPE"0402"
SEC"1"
ROOM"BMC"
BOM_COST"SM_CONTROLLER"
CDS_LIB"mstr_discrete"
CDS_LOCATION"R25W96";
"B"
$PN"2"21;
"A"
$PN"1"1;
%"RES"
"1","(-600,-200)","0","mstr_discrete","I146";
;
CDS_SEC"1"
WATTAGE"1/16W"
PART_NUMBER"G21796-072"
TOLERANCE"1%"
VALUE"4.75K"
LOCATION"R25W97"
MATERIAL"EMPTY"
PACK_TYPE"0402"
ROOM"BMC"
BOM_COST"SM_CONTROLLER"
SEC"1"
SEC_TYPE"0402"
CDS_LIB"mstr_discrete"
CDS_LOCATION"R25W97";
"B"
$PN"2"30;
"A"
$PN"1"1;
%"P3V3_STBY"
"1","(-1000,550)","0","mstr_symbols","I147";
;
CDS_LIB"mstr_symbols"
VOLTAGE"3.3V"
SIZE"1B"
BODY_TYPE"PLUMBING"
HDL_POWER"P3V3_STBY";
"G\NAC"1;
%"RES"
"1","(-600,-1100)","0","mstr_discrete","I175";
;
CDS_SEC"1"
WATTAGE"1/16W"
PART_NUMBER"G21796-072"
TOLERANCE"1%"
VALUE"4.75K"
PACK_TYPE"0402"
MATERIAL"EMPTY"
LOCATION"R25W106"
BOM_COST"SM_CONTROLLER"
ROOM"BMC"
CDS_LIB"mstr_discrete"
CDS_LOCATION"R25W106"
SEC"1"
SEC_TYPE"0402";
"B"
$PN"2"27;
"A"
$PN"1"1;
%"RES"
"1","(-600,-1500)","0","mstr_discrete","I180";
;
CDS_SEC"1"
PACK_TYPE"0402"
TOLERANCE"1%"
WATTAGE"1/16W"
VALUE"4.75K"
LOCATION"R25W111"
MATERIAL"EMPTY"
PART_NUMBER"G21796-072"
BOM_COST"SM_CONTROLLER"
ROOM"BMC"
CDS_LIB"mstr_discrete"
CDS_LOCATION"R25W111"
SEC"1"
SEC_TYPE"0402";
"B"
$PN"2"25;
"A"
$PN"1"1;
%"GND"
"1","(-900,-950)","0","mstr_symbols","I186";
;
VOLTAGE"0.0V"
SIZE"1B"
CDS_LIB"mstr_symbols"
BODY_TYPE"PLUMBING"
HDL_POWER"GND";
"A\NAC"2;
%"RES"
"2","(-600,-850)","1","mstr_discrete","I189";
;
CDS_SEC"1"
LOCATION"R25W116"
MATERIAL"EMPTY"
VALUE"3.32K"
TOLERANCE"1%"
WATTAGE"1/16W"
PART_NUMBER"G21796-027"
PACK_TYPE"0402"
CDS_LIB"mstr_discrete"
ROOM"NIC_SPRV"
BOM_COST"NT_GBE_BASE"
SEC_TYPE"0402"
SEC"1"
CDS_LOCATION"R25W116";
"A"
$PN"1"2;
"B"
$PN"2"28;
%"RES"
"1","(-600,-1900)","0","mstr_discrete","I190";
;
PART_NUMBER"G21796-072"
TOLERANCE"1%"
PACK_TYPE"0402"
MATERIAL"CHIP"
WATTAGE"1/16W"
VALUE"4.75K"
LOCATION"R25W107"
CDS_SEC"1"
SEC_TYPE"0402"
SEC"1"
ROOM"BMC"
BOM_COST"SM_CONTROLLER"
CDS_LIB"mstr_discrete"
CDS_LOCATION"R25W107";
"B"
$PN"2"26;
"A"
$PN"1"1;
%"RES"
"1","(-600,-2100)","0","mstr_discrete","I191";
;
PACK_TYPE"0402"
LOCATION"R25W108"
WATTAGE"1/16W"
PART_NUMBER"G21796-072"
TOLERANCE"1%"
VALUE"4.75K"
MATERIAL"EMPTY"
CDS_LOCATION"R25W108"
CDS_SEC"1"
BOM_COST"SM_CONTROLLER"
ROOM"BMC"
CDS_LIB"mstr_discrete"
SEC"1"
SEC_TYPE"0402";
"B"
$PN"2"13;
"A"
$PN"1"1;
%"RES"
"1","(-600,-400)","0","mstr_discrete","I196";
;
CDS_SEC"1"
TOLERANCE"1%"
VALUE"4.75K"
LOCATION"R25W105"
PACK_TYPE"0402"
WATTAGE"1/16W"
PART_NUMBER"G21796-072"
MATERIAL"EMPTY"
BOM_COST"SM_CONTROLLER"
ROOM"BMC"
CDS_LIB"mstr_discrete"
CDS_LOCATION"R25W105"
SEC"1"
SEC_TYPE"0402";
"B"
$PN"2"29;
"A"
$PN"1"1;
%"GND"
"1","(-900,-1400)","0","mstr_symbols","I198";
;
CDS_LIB"mstr_symbols"
SIZE"1B"
VOLTAGE"0.0V"
BODY_TYPE"PLUMBING"
HDL_POWER"GND";
"A\NAC"3;
%"RES"
"1","(-600,-1300)","0","mstr_discrete","I199";
;
CDS_SEC"1"
CDS_LOCATION"R25W146"
PACK_TYPE"0402"
VALUE"4.75K"
MATERIAL"CHIP"
LOCATION"R25W146"
PART_NUMBER"G21796-072"
WATTAGE"1/16W"
TOLERANCE"1%"
BOM_COST"SM_CONTROLLER"
ROOM"BMC"
CDS_LIB"mstr_discrete"
SEC"1"
SEC_TYPE"0402";
"B"
$PN"2"27;
"A"
$PN"1"3;
%"RES"
"1","(1850,-200)","0","mstr_discrete","I209";
;
CDS_SEC"1"
CDS_LOCATION"R25W98"
VALUE"4.75K"
MATERIAL"EMPTY"
LOCATION"R25W98"
WATTAGE"1/16W"
TOLERANCE"1%"
PART_NUMBER"G21796-072"
PACK_TYPE"0402"
BOM_COST"SM_CONTROLLER"
ROOM"BMC"
CDS_LIB"mstr_discrete"
SEC"1"
SEC_TYPE"0402";
"B"
$PN"2"20;
"A"
$PN"1"9;
%"RES"
"1","(1850,-400)","0","mstr_discrete","I210";
;
CDS_SEC"1"
VALUE"4.75K"
PART_NUMBER"G21796-072"
MATERIAL"EMPTY"
WATTAGE"1/16W"
TOLERANCE"1%"
PACK_TYPE"0402"
LOCATION"R25W99"
CDS_LIB"mstr_discrete"
ROOM"BMC"
BOM_COST"SM_CONTROLLER"
CDS_LOCATION"R25W99"
SEC"1"
SEC_TYPE"0402";
"B"
$PN"2"19;
"A"
$PN"1"9;
%"RES"
"1","(1850,-600)","0","mstr_discrete","I211";
;
MATERIAL"CHIP"
TOLERANCE"1%"
WATTAGE"1/16W"
VALUE"4.75K"
LOCATION"R25W100"
PACK_TYPE"0402"
PART_NUMBER"G21796-072"
CDS_LOCATION"R25W100"
ROOM"BMC"
BOM_COST"SM_CONTROLLER"
CDS_LIB"mstr_discrete"
SEC"1"
SEC_TYPE"0402"
CDS_SEC"1";
"B"
$PN"2"15;
"A"
$PN"1"9;
%"RES"
"1","(1850,-1200)","0","mstr_discrete","I214";
;
PART_NUMBER"G21796-072"
WATTAGE"1/16W"
PACK_TYPE"0402"
MATERIAL"EMPTY"
TOLERANCE"1%"
LOCATION"R25W103"
VALUE"4.75K"
CDS_SEC"1"
SEC_TYPE"0402"
SEC"1"
CDS_LIB"mstr_discrete"
CDS_LOCATION"R25W103"
ROOM"BMC"
BOM_COST"SM_CONTROLLER";
"B"
$PN"2"17;
"A"
$PN"1"9;
%"RES"
"1","(1850,-1400)","0","mstr_discrete","I215";
;
PACK_TYPE"0402"
PART_NUMBER"G21796-072"
WATTAGE"1/16W"
TOLERANCE"1%"
MATERIAL"CHIP"
LOCATION"R25W104"
VALUE"4.75K"
CDS_SEC"1"
SEC_TYPE"0402"
SEC"1"
ROOM"BMC"
BOM_COST"SM_CONTROLLER"
CDS_LIB"mstr_discrete"
CDS_LOCATION"R25W104";
"B"
$PN"2"16;
"A"
$PN"1"9;
%"RES"
"1","(-600,-2300)","0","mstr_discrete","I216";
;
CDS_SEC"1"
CDS_LOCATION"R25W148"
WATTAGE"1/16W"
VALUE"4.75K"
PACK_TYPE"0402"
MATERIAL"CHIP"
LOCATION"R25W148"
PART_NUMBER"G21796-072"
TOLERANCE"1%"
SEC_TYPE"0402"
SEC"1"
CDS_LIB"mstr_discrete"
ROOM"BMC"
BOM_COST"SM_CONTROLLER";
"B"
$PN"2"13;
"A"
$PN"1"4;
%"GND"
"1","(-900,-2400)","0","mstr_symbols","I217";
;
VOLTAGE"0.0V"
SIZE"1B"
CDS_LIB"mstr_symbols"
BODY_TYPE"PLUMBING"
HDL_POWER"GND";
"A\NAC"4;
%"RES"
"1","(-600,-2500)","0","mstr_discrete","I218";
;
PART_NUMBER"G21796-072"
WATTAGE"1/16W"
TOLERANCE"1%"
VALUE"4.75K"
MATERIAL"EMPTY"
LOCATION"R25W114"
PACK_TYPE"0402"
CDS_SEC"1"
SEC_TYPE"0402"
SEC"1"
CDS_LOCATION"R25W114"
CDS_LIB"mstr_discrete"
ROOM"BMC"
BOM_COST"SM_CONTROLLER";
"B"
$PN"2"11;
"A"
$PN"1"1;
%"RES"
"1","(-600,-2700)","0","mstr_discrete","I219";
;
CDS_SEC"1"
CDS_LOCATION"R25W149"
PART_NUMBER"G21796-072"
MATERIAL"CHIP"
PACK_TYPE"0402"
WATTAGE"1/16W"
VALUE"4.75K"
TOLERANCE"1%"
LOCATION"R25W149"
SEC"1"
SEC_TYPE"0402"
BOM_COST"SM_CONTROLLER"
ROOM"BMC"
CDS_LIB"mstr_discrete";
"B"
$PN"2"11;
"A"
$PN"1"5;
%"GND"
"1","(-900,-2800)","0","mstr_symbols","I227";
;
CDS_LIB"mstr_symbols"
SIZE"1B"
VOLTAGE"0.0V"
BODY_TYPE"PLUMBING"
HDL_POWER"GND";
"A\NAC"5;
%"RES"
"1","(-600,-3100)","0","mstr_discrete","I228";
;
VALUE"4.75K"
TOLERANCE"1%"
WATTAGE"1/16W"
LOCATION"R25W112"
MATERIAL"EMPTY"
PART_NUMBER"G21796-072"
PACK_TYPE"0402"
SEC_TYPE"0402"
SEC"1"
CDS_LOCATION"R25W112"
CDS_LIB"mstr_discrete"
ROOM"BMC"
BOM_COST"SM_CONTROLLER"
CDS_SEC"1";
"B"
$PN"2"12;
"A"
$PN"1"1;
%"RES"
"1","(-600,-3300)","0","mstr_discrete","I229";
;
CDS_SEC"1"
CDS_LOCATION"R25W150"
TOLERANCE"1%"
VALUE"4.75K"
PART_NUMBER"G21796-072"
PACK_TYPE"0402"
WATTAGE"1/16W"
LOCATION"R25W150"
MATERIAL"CHIP"
SEC"1"
SEC_TYPE"0402"
BOM_COST"SM_CONTROLLER"
ROOM"BMC"
CDS_LIB"mstr_discrete";
"B"
$PN"2"12;
"A"
$PN"1"6;
%"RES"
"1","(-600,-3500)","0","mstr_discrete","I230";
;
PACK_TYPE"0402"
PART_NUMBER"G21796-072"
WATTAGE"1/16W"
TOLERANCE"1%"
VALUE"4.75K"
LOCATION"R25W113"
MATERIAL"EMPTY"
CDS_SEC"1"
BOM_COST"SM_CONTROLLER"
ROOM"BMC"
CDS_LIB"mstr_discrete"
CDS_LOCATION"R25W113"
SEC"1"
SEC_TYPE"0402";
"B"
$PN"2"24;
"A"
$PN"1"1;
%"GND"
"1","(-900,-3400)","0","mstr_symbols","I231";
;
CDS_LIB"mstr_symbols"
SIZE"1B"
VOLTAGE"0.0V"
BODY_TYPE"PLUMBING"
HDL_POWER"GND";
"A\NAC"6;
%"RES"
"1","(-600,-3650)","0","mstr_discrete","I232";
;
CDS_SEC"1"
CDS_LOCATION"R25W151"
PACK_TYPE"0402"
PART_NUMBER"G21796-072"
WATTAGE"1/16W"
TOLERANCE"1%"
VALUE"4.75K"
LOCATION"R25W151"
MATERIAL"CHIP"
CDS_LIB"mstr_discrete"
ROOM"BMC"
BOM_COST"SM_CONTROLLER"
SEC_TYPE"0402"
SEC"1";
"B"
$PN"2"24;
"A"
$PN"1"7;
%"RES"
"1","(1850,400)","0","mstr_discrete","I233";
;
MATERIAL"EMPTY"
VALUE"4.75K"
TOLERANCE"1%"
PART_NUMBER"G21796-072"
WATTAGE"1/16W"
PACK_TYPE"0402"
LOCATION"R25W110"
CDS_LOCATION"R25W110"
SEC_TYPE"0402"
SEC"1"
CDS_LIB"mstr_discrete"
ROOM"BMC"
BOM_COST"SM_CONTROLLER"
CDS_SEC"1";
"B"
$PN"2"22;
"A"
$PN"1"9;
%"RES"
"1","(1850,200)","0","mstr_discrete","I234";
;
CDS_SEC"1"
CDS_LOCATION"R25W152"
PACK_TYPE"0402"
TOLERANCE"1%"
VALUE"4.75K"
LOCATION"R25W152"
WATTAGE"1/16W"
PART_NUMBER"G21796-072"
MATERIAL"CHIP"
CDS_LIB"mstr_discrete"
ROOM"BMC"
BOM_COST"SM_CONTROLLER"
SEC_TYPE"0402"
SEC"1";
"B"
$PN"2"22;
"A"
$PN"1"8;
%"GND"
"1","(-900,-3750)","0","mstr_symbols","I235";
;
CDS_LIB"mstr_symbols"
SIZE"1B"
VOLTAGE"0.0V"
BODY_TYPE"PLUMBING"
HDL_POWER"GND";
"A\NAC"7;
%"RES"
"1","(1850,0)","0","mstr_discrete","I236";
;
CDS_SEC"1"
CDS_LOCATION"R25W109"
PART_NUMBER"G21796-072"
TOLERANCE"1%"
LOCATION"R25W109"
MATERIAL"CHIP"
VALUE"4.75K"
PACK_TYPE"0402"
WATTAGE"1/16W"
CDS_LIB"mstr_discrete"
ROOM"BMC"
BOM_COST"SM_CONTROLLER"
SEC_TYPE"0402"
SEC"1";
"B"
$PN"2"23;
"A"
$PN"1"9;
%"GND"
"1","(1550,100)","0","mstr_symbols","I237";
;
VOLTAGE"0.0V"
SIZE"1B"
CDS_LIB"mstr_symbols"
BODY_TYPE"PLUMBING"
HDL_POWER"GND";
"A\NAC"8;
%"P3V3_STBY"
"1","(1450,550)","0","mstr_symbols","I238";
;
SIZE"1B"
VOLTAGE"3.3V"
CDS_LIB"mstr_symbols"
BODY_TYPE"PLUMBING"
HDL_POWER"P3V3_STBY";
"G\NAC"9;
%"RES"
"1","(1850,-1000)","0","mstr_discrete","I239";
;
PACK_TYPE"0402"
WATTAGE"1/16W"
TOLERANCE"1%"
LOCATION"R25W102"
PART_NUMBER"G21796-072"
MATERIAL"EMPTY"
VALUE"4.75K"
CDS_LOCATION"R25W102"
BOM_COST"SM_CONTROLLER"
ROOM"BMC"
CDS_LIB"mstr_discrete"
SEC"1"
SEC_TYPE"0402"
CDS_SEC"1";
"B"
$PN"2"18;
"A"
$PN"1"9;
%"RES"
"2","(-600,-650)","1","mstr_discrete","I240";
;
CDS_SEC"1"
LOCATION"R25W156"
WATTAGE"1/16W"
VALUE"3.32K"
MATERIAL"EMPTY"
PACK_TYPE"0402"
TOLERANCE"1%"
PART_NUMBER"G21796-027"
CDS_LIB"mstr_discrete"
ROOM"NIC_SPRV"
BOM_COST"NT_GBE_BASE"
SEC_TYPE"0402"
SEC"1"
CDS_LOCATION"R25W156";
"A"
$PN"1"1;
"B"
$PN"2"28;
%"RES"
"1","(1850,-800)","0","mstr_discrete","I241";
;
MATERIAL"EMPTY"
PART_NUMBER"G21796-072"
VALUE"4.75K"
PACK_TYPE"0402"
LOCATION"R25W101"
WATTAGE"1/16W"
TOLERANCE"1%"
CDS_LOCATION"R25W101"
CDS_SEC"1"
SEC_TYPE"0402"
SEC"1"
CDS_LIB"mstr_discrete"
ROOM"BMC"
BOM_COST"SM_CONTROLLER";
"B"
$PN"2"14;
"A"
$PN"1"9;
%"RES"
"1","(-600,-2900)","0","mstr_discrete","I242";
;
LOCATION"R25W115"
MATERIAL"EMPTY"
VALUE"4.75K"
TOLERANCE"1%"
WATTAGE"1/16W"
PART_NUMBER"G21796-072"
PACK_TYPE"0402"
CDS_LOCATION"R25W115"
SEC_TYPE"0402"
SEC"1"
CDS_LIB"mstr_discrete"
ROOM"BMC"
BOM_COST"SM_CONTROLLER"
CDS_SEC"1";
"B"
$PN"2"10;
"A"
$PN"1"1;
END.
